(kicad_pcb
	(version 20260206)
	(generator "pcbnew")
	(generator_version "10.0")
	(general
		(thickness 1.6)
		(legacy_teardrops no)
	)
	(paper "A4")
	(title_block
		(title "12092022_DA0F0TMDCD0_F0T_Management_Board_D_brd_V3_OCP.brd")
		(comment 1 "Grand Teton / footprints 826-832 of 1440")
	)
	(layers
		(0 "F.Cu" signal "TOP")
		(4 "In1.Cu" signal "GND")
		(6 "In2.Cu" signal "IN1")
		(8 "In3.Cu" signal "GND1")
		(10 "In4.Cu" signal "IN2")
		(12 "In5.Cu" signal "VCC")
		(14 "In6.Cu" signal "VCC1")
		(16 "In7.Cu" signal "IN3")
		(18 "In8.Cu" signal "GND2")
		(20 "In9.Cu" signal "IN4")
		(22 "In10.Cu" signal "GND3")
		(2 "B.Cu" signal "BOTTOM")
		(9 "F.Adhes" user "F.Adhesive")
		(11 "B.Adhes" user "B.Adhesive")
		(13 "F.Paste" user "Package Geometry/Pastemask Top")
		(15 "B.Paste" user "Package Geometry/Pastemask Bottom")
		(5 "F.SilkS" user "Ref Des/Silkscreen Top")
		(7 "B.SilkS" user "Ref Des/Silkscreen Bottom")
		(1 "F.Mask" user "Board Geometry/Soldermask Top")
		(3 "B.Mask" user "Board Geometry/Soldermask Bottom")
		(17 "Dwgs.User" user "User.Drawings")
		(19 "Cmts.User" user "User.Comments")
		(21 "Eco1.User" user "User.Eco1")
		(23 "Eco2.User" user "User.Eco2")
		(25 "Edge.Cuts" user "Board Geometry/Outline")
		(27 "Margin" user)
		(31 "F.CrtYd" user "Package Geometry/Place Bound Top")
		(29 "B.CrtYd" user "Package Geometry/Place Bound Bottom")
		(35 "F.Fab" user "Ref Des/Assembly Top")
		(33 "B.Fab" user "Ref Des/Assembly Bottom")
	)
	(footprint ""
		(layer "B.Cu")
		(at 84.9122 -67.691)
		(property "Reference" "DM7"
			(at 0 0 0)
			(layer "B.SilkS")
			(hide yes)
			(effects
				(font
					(size 1.27 1.27)
				)
				(justify mirror)
			)
		)
		(property "Value" ""
			(at 0 0 0)
			(layer "B.Fab")
			(effects
				(font
					(size 1.27 1.27)
				)
				(justify mirror)
			)
		)
		(duplicate_pad_numbers_are_jumpers no)
	)
	(footprint ""
		(layer "B.Cu")
		(at 21.859494 -95.187008 90)
		(property "Reference" "C187"
			(at 0 0 90)
			(layer "B.SilkS")
			(hide yes)
			(effects
				(font
					(size 1.27 1.27)
				)
				(justify mirror)
			)
		)
		(property "Value" ""
			(at 0 0 90)
			(layer "B.Fab")
			(effects
				(font
					(size 1.27 1.27)
				)
				(justify mirror)
			)
		)
		(duplicate_pad_numbers_are_jumpers no)
		(fp_line
			(start 0.69215 -0.2921)
			(end -0.69215 -0.2921)
			(stroke
				(width 0.1524)
				(type default)
			)
			(layer "B.SilkS")
		)
		(fp_line
			(start -0.69215 -0.2921)
			(end -0.69215 0.2921)
			(stroke
				(width 0.1524)
				(type default)
			)
			(layer "B.SilkS")
		)
		(fp_line
			(start 0.69215 0.2921)
			(end 0.69215 -0.2921)
			(stroke
				(width 0.1524)
				(type default)
			)
			(layer "B.SilkS")
		)
		(fp_line
			(start -0.69215 0.2921)
			(end 0.69215 0.2921)
			(stroke
				(width 0.1524)
				(type default)
			)
			(layer "B.SilkS")
		)
		(fp_line
			(start 0.51435 -0.2794)
			(end -0.51435 -0.2794)
			(stroke
				(width 0.1)
				(type default)
			)
			(layer "B.Fab")
		)
		(fp_line
			(start -0.51435 -0.2794)
			(end -0.51435 0.2794)
			(stroke
				(width 0.1)
				(type default)
			)
			(layer "B.Fab")
		)
		(fp_line
			(start 0.51435 0.2794)
			(end 0.51435 -0.2794)
			(stroke
				(width 0.1)
				(type default)
			)
			(layer "B.Fab")
		)
		(fp_line
			(start -0.51435 0.2794)
			(end 0.51435 0.2794)
			(stroke
				(width 0.1)
				(type default)
			)
			(layer "B.Fab")
		)
		(pad "1" smd circle
			(at 0.40005 0 270)
			(size 0 0)
			(layers "B.Cu" "B.Mask" "B.Paste")
			(net "VCCIO2")
		)
		(pad "2" smd circle
			(at -0.40005 0 270)
			(size 0 0)
			(layers "B.Cu" "B.Mask" "B.Paste")
			(net "GND")
		)
		(zone
			(layer "B.Cu")
			(hatch none 0.5)
			(connect_pads
				(clearance 0)
			)
			(min_thickness 0.25)
			(keepout
				(tracks not_allowed)
				(vias allowed)
				(pads allowed)
				(copperpour not_allowed)
				(footprints allowed)
			)
			(placement
				(enabled no)
				(sheetname "")
			)
			(fill
				(thermal_gap 0.5)
				(thermal_bridge_width 0.5)
				(island_removal_mode 0)
			)
			(polygon
				(pts
					(xy 21.947124 -95.377508) (xy 22.00529 -95.286068) (xy 22.00529 -95.086678) (xy 21.947124 -94.996508)
					(xy 21.771864 -94.996508) (xy 21.713444 -95.086678) (xy 21.713444 -95.286068) (xy 21.77161 -95.377508)
				)
			)
		)
	)
	(footprint ""
		(layer "B.Cu")
		(at 12.319 -94.488 180)
		(property "Reference" "R457"
			(at 0 0 0)
			(layer "B.SilkS")
			(hide yes)
			(effects
				(font
					(size 1.27 1.27)
				)
				(justify mirror)
			)
		)
		(property "Value" ""
			(at 0 0 0)
			(layer "B.Fab")
			(effects
				(font
					(size 1.27 1.27)
				)
				(justify mirror)
			)
		)
		(duplicate_pad_numbers_are_jumpers no)
		(fp_line
			(start 0.7874 0.4064)
			(end 0.7874 -0.4064)
			(stroke
				(width 0.1524)
				(type default)
			)
			(layer "B.SilkS")
		)
		(fp_line
			(start 0.7874 -0.4064)
			(end -0.7874 -0.4064)
			(stroke
				(width 0.1524)
				(type default)
			)
			(layer "B.SilkS")
		)
		(fp_line
			(start -0.7874 0.4064)
			(end 0.7874 0.4064)
			(stroke
				(width 0.1524)
				(type default)
			)
			(layer "B.SilkS")
		)
		(fp_line
			(start -0.7874 -0.4064)
			(end -0.7874 0.4064)
			(stroke
				(width 0.1524)
				(type default)
			)
			(layer "B.SilkS")
		)
		(fp_line
			(start 0.67945 0.3048)
			(end 0.67945 -0.305054)
			(stroke
				(width 0.1)
				(type default)
			)
			(layer "B.Fab")
		)
		(fp_line
			(start 0.67945 -0.305054)
			(end 0.12065 -0.305054)
			(stroke
				(width 0.1)
				(type default)
			)
			(layer "B.Fab")
		)
		(fp_line
			(start 0.12065 0.3048)
			(end 0.67945 0.3048)
			(stroke
				(width 0.1)
				(type default)
			)
			(layer "B.Fab")
		)
		(fp_line
			(start 0.12065 0.2794)
			(end 0.12065 0.3048)
			(stroke
				(width 0.1)
				(type default)
			)
			(layer "B.Fab")
		)
		(fp_line
			(start 0.12065 -0.2794)
			(end -0.12065 -0.2794)
			(stroke
				(width 0.1)
				(type default)
			)
			(layer "B.Fab")
		)
		(fp_line
			(start 0.12065 -0.305054)
			(end 0.12065 -0.2794)
			(stroke
				(width 0.1)
				(type default)
			)
			(layer "B.Fab")
		)
		(fp_line
			(start -0.120396 0.3048)
			(end -0.120396 0.2794)
			(stroke
				(width 0.1)
				(type default)
			)
			(layer "B.Fab")
		)
		(fp_line
			(start -0.120396 0.2794)
			(end 0.12065 0.2794)
			(stroke
				(width 0.1)
				(type default)
			)
			(layer "B.Fab")
		)
		(fp_line
			(start -0.12065 -0.2794)
			(end -0.12065 -0.3048)
			(stroke
				(width 0.1)
				(type default)
			)
			(layer "B.Fab")
		)
		(fp_line
			(start -0.12065 -0.3048)
			(end -0.67945 -0.3048)
			(stroke
				(width 0.1)
				(type default)
			)
			(layer "B.Fab")
		)
		(fp_line
			(start -0.67945 0.3048)
			(end -0.120396 0.3048)
			(stroke
				(width 0.1)
				(type default)
			)
			(layer "B.Fab")
		)
		(fp_line
			(start -0.67945 -0.3048)
			(end -0.67945 0.3048)
			(stroke
				(width 0.1)
				(type default)
			)
			(layer "B.Fab")
		)
		(pad "1" smd circle
			(at 0.40005 0)
			(size 0 0)
			(layers "B.Cu" "B.Mask" "B.Paste")
			(net "SMB_BMC_ALERT10_N")
		)
		(pad "2" smd circle
			(at -0.40005 0)
			(size 0 0)
			(layers "B.Cu" "B.Mask" "B.Paste")
			(net "SMB_BMC_ALERT10_R1_N")
		)
	)
	(footprint ""
		(layer "B.Cu")
		(at 18.923 -101.981 -90)
		(property "Reference" "R322"
			(at 0 0 90)
			(layer "B.SilkS")
			(hide yes)
			(effects
				(font
					(size 1.27 1.27)
				)
				(justify mirror)
			)
		)
		(property "Value" ""
			(at 0 0 90)
			(layer "B.Fab")
			(effects
				(font
					(size 1.27 1.27)
				)
				(justify mirror)
			)
		)
		(duplicate_pad_numbers_are_jumpers no)
		(fp_line
			(start -0.7874 0.4064)
			(end 0.7874 0.4064)
			(stroke
				(width 0.1524)
				(type default)
			)
			(layer "B.SilkS")
		)
		(fp_line
			(start 0.7874 0.4064)
			(end 0.7874 -0.4064)
			(stroke
				(width 0.1524)
				(type default)
			)
			(layer "B.SilkS")
		)
		(fp_line
			(start -0.7874 -0.4064)
			(end -0.7874 0.4064)
			(stroke
				(width 0.1524)
				(type default)
			)
			(layer "B.SilkS")
		)
		(fp_line
			(start 0.7874 -0.4064)
			(end -0.7874 -0.4064)
			(stroke
				(width 0.1524)
				(type default)
			)
			(layer "B.SilkS")
		)
		(fp_line
			(start -0.67945 0.3048)
			(end -0.120396 0.3048)
			(stroke
				(width 0.1)
				(type default)
			)
			(layer "B.Fab")
		)
		(fp_line
			(start -0.120396 0.3048)
			(end -0.120396 0.2794)
			(stroke
				(width 0.1)
				(type default)
			)
			(layer "B.Fab")
		)
		(fp_line
			(start 0.12065 0.3048)
			(end 0.67945 0.3048)
			(stroke
				(width 0.1)
				(type default)
			)
			(layer "B.Fab")
		)
		(fp_line
			(start 0.67945 0.3048)
			(end 0.67945 -0.305054)
			(stroke
				(width 0.1)
				(type default)
			)
			(layer "B.Fab")
		)
		(fp_line
			(start -0.120396 0.2794)
			(end 0.12065 0.2794)
			(stroke
				(width 0.1)
				(type default)
			)
			(layer "B.Fab")
		)
		(fp_line
			(start 0.12065 0.2794)
			(end 0.12065 0.3048)
			(stroke
				(width 0.1)
				(type default)
			)
			(layer "B.Fab")
		)
		(fp_line
			(start -0.12065 -0.2794)
			(end -0.12065 -0.3048)
			(stroke
				(width 0.1)
				(type default)
			)
			(layer "B.Fab")
		)
		(fp_line
			(start 0.12065 -0.2794)
			(end -0.12065 -0.2794)
			(stroke
				(width 0.1)
				(type default)
			)
			(layer "B.Fab")
		)
		(fp_line
			(start -0.67945 -0.3048)
			(end -0.67945 0.3048)
			(stroke
				(width 0.1)
				(type default)
			)
			(layer "B.Fab")
		)
		(fp_line
			(start -0.12065 -0.3048)
			(end -0.67945 -0.3048)
			(stroke
				(width 0.1)
				(type default)
			)
			(layer "B.Fab")
		)
		(fp_line
			(start 0.12065 -0.305054)
			(end 0.12065 -0.2794)
			(stroke
				(width 0.1)
				(type default)
			)
			(layer "B.Fab")
		)
		(fp_line
			(start 0.67945 -0.305054)
			(end 0.12065 -0.305054)
			(stroke
				(width 0.1)
				(type default)
			)
			(layer "B.Fab")
		)
		(pad "1" smd circle
			(at 0.40005 0 90)
			(size 0 0)
			(layers "B.Cu" "B.Mask" "B.Paste")
			(net "PWRGD_P3V3_RGM_R1")
		)
		(pad "2" smd circle
			(at -0.40005 0 90)
			(size 0 0)
			(layers "B.Cu" "B.Mask" "B.Paste")
			(net "PWRGD_P3V3_RGM")
		)
	)
	(footprint ""
		(layer "B.Cu")
		(at 71.069708 -29.817314)
		(property "Reference" "C192"
			(at 0 0 0)
			(layer "B.SilkS")
			(hide yes)
			(effects
				(font
					(size 1.27 1.27)
				)
				(justify mirror)
			)
		)
		(property "Value" ""
			(at 0 0 0)
			(layer "B.Fab")
			(effects
				(font
					(size 1.27 1.27)
				)
				(justify mirror)
			)
		)
		(duplicate_pad_numbers_are_jumpers no)
		(fp_line
			(start -0.7874 -0.4064)
			(end -0.7874 0.4064)
			(stroke
				(width 0.1524)
				(type default)
			)
			(layer "B.SilkS")
		)
		(fp_line
			(start -0.7874 0.4064)
			(end 0.7874 0.4064)
			(stroke
				(width 0.1524)
				(type default)
			)
			(layer "B.SilkS")
		)
		(fp_line
			(start 0.7874 -0.4064)
			(end -0.7874 -0.4064)
			(stroke
				(width 0.1524)
				(type default)
			)
			(layer "B.SilkS")
		)
		(fp_line
			(start 0.7874 0.4064)
			(end 0.7874 -0.4064)
			(stroke
				(width 0.1524)
				(type default)
			)
			(layer "B.SilkS")
		)
		(fp_line
			(start -0.67945 -0.3048)
			(end -0.67945 0.3048)
			(stroke
				(width 0.1)
				(type default)
			)
			(layer "B.Fab")
		)
		(fp_line
			(start -0.67945 0.3048)
			(end -0.120396 0.3048)
			(stroke
				(width 0.1)
				(type default)
			)
			(layer "B.Fab")
		)
		(fp_line
			(start -0.12065 -0.3048)
			(end -0.67945 -0.3048)
			(stroke
				(width 0.1)
				(type default)
			)
			(layer "B.Fab")
		)
		(fp_line
			(start -0.12065 -0.2794)
			(end -0.12065 -0.3048)
			(stroke
				(width 0.1)
				(type default)
			)
			(layer "B.Fab")
		)
		(fp_line
			(start -0.120396 0.2794)
			(end 0.12065 0.2794)
			(stroke
				(width 0.1)
				(type default)
			)
			(layer "B.Fab")
		)
		(fp_line
			(start -0.120396 0.3048)
			(end -0.120396 0.2794)
			(stroke
				(width 0.1)
				(type default)
			)
			(layer "B.Fab")
		)
		(fp_line
			(start 0.12065 -0.305054)
			(end 0.12065 -0.2794)
			(stroke
				(width 0.1)
				(type default)
			)
			(layer "B.Fab")
		)
		(fp_line
			(start 0.12065 -0.2794)
			(end -0.12065 -0.2794)
			(stroke
				(width 0.1)
				(type default)
			)
			(layer "B.Fab")
		)
		(fp_line
			(start 0.12065 0.2794)
			(end 0.12065 0.3048)
			(stroke
				(width 0.1)
				(type default)
			)
			(layer "B.Fab")
		)
		(fp_line
			(start 0.12065 0.3048)
			(end 0.67945 0.3048)
			(stroke
				(width 0.1)
				(type default)
			)
			(layer "B.Fab")
		)
		(fp_line
			(start 0.67945 -0.305054)
			(end 0.12065 -0.305054)
			(stroke
				(width 0.1)
				(type default)
			)
			(layer "B.Fab")
		)
		(fp_line
			(start 0.67945 0.3048)
			(end 0.67945 -0.305054)
			(stroke
				(width 0.1)
				(type default)
			)
			(layer "B.Fab")
		)
		(pad "1" smd circle
			(at 0.40005 0 180)
			(size 0 0)
			(layers "B.Cu" "B.Mask" "B.Paste")
			(net "P3V3_AUX")
		)
		(pad "2" smd circle
			(at -0.40005 0 180)
			(size 0 0)
			(layers "B.Cu" "B.Mask" "B.Paste")
			(net "GND")
		)
	)
	(footprint ""
		(layer "B.Cu")
		(at 39.930832 -48.026828)
		(property "Reference" "R424"
			(at 0 0 0)
			(layer "B.SilkS")
			(hide yes)
			(effects
				(font
					(size 1.27 1.27)
				)
				(justify mirror)
			)
		)
		(property "Value" ""
			(at 0 0 0)
			(layer "B.Fab")
			(effects
				(font
					(size 1.27 1.27)
				)
				(justify mirror)
			)
		)
		(duplicate_pad_numbers_are_jumpers no)
		(fp_line
			(start -0.7874 -0.4064)
			(end -0.7874 0.4064)
			(stroke
				(width 0.1524)
				(type default)
			)
			(layer "B.SilkS")
		)
		(fp_line
			(start -0.7874 0.4064)
			(end 0.7874 0.4064)
			(stroke
				(width 0.1524)
				(type default)
			)
			(layer "B.SilkS")
		)
		(fp_line
			(start 0.7874 -0.4064)
			(end -0.7874 -0.4064)
			(stroke
				(width 0.1524)
				(type default)
			)
			(layer "B.SilkS")
		)
		(fp_line
			(start 0.7874 0.4064)
			(end 0.7874 -0.4064)
			(stroke
				(width 0.1524)
				(type default)
			)
			(layer "B.SilkS")
		)
		(fp_line
			(start -0.67945 -0.3048)
			(end -0.67945 0.3048)
			(stroke
				(width 0.1)
				(type default)
			)
			(layer "B.Fab")
		)
		(fp_line
			(start -0.67945 0.3048)
			(end -0.120396 0.3048)
			(stroke
				(width 0.1)
				(type default)
			)
			(layer "B.Fab")
		)
		(fp_line
			(start -0.12065 -0.3048)
			(end -0.67945 -0.3048)
			(stroke
				(width 0.1)
				(type default)
			)
			(layer "B.Fab")
		)
		(fp_line
			(start -0.12065 -0.2794)
			(end -0.12065 -0.3048)
			(stroke
				(width 0.1)
				(type default)
			)
			(layer "B.Fab")
		)
		(fp_line
			(start -0.120396 0.2794)
			(end 0.12065 0.2794)
			(stroke
				(width 0.1)
				(type default)
			)
			(layer "B.Fab")
		)
		(fp_line
			(start -0.120396 0.3048)
			(end -0.120396 0.2794)
			(stroke
				(width 0.1)
				(type default)
			)
			(layer "B.Fab")
		)
		(fp_line
			(start 0.12065 -0.305054)
			(end 0.12065 -0.2794)
			(stroke
				(width 0.1)
				(type default)
			)
			(layer "B.Fab")
		)
		(fp_line
			(start 0.12065 -0.2794)
			(end -0.12065 -0.2794)
			(stroke
				(width 0.1)
				(type default)
			)
			(layer "B.Fab")
		)
		(fp_line
			(start 0.12065 0.2794)
			(end 0.12065 0.3048)
			(stroke
				(width 0.1)
				(type default)
			)
			(layer "B.Fab")
		)
		(fp_line
			(start 0.12065 0.3048)
			(end 0.67945 0.3048)
			(stroke
				(width 0.1)
				(type default)
			)
			(layer "B.Fab")
		)
		(fp_line
			(start 0.67945 -0.305054)
			(end 0.12065 -0.305054)
			(stroke
				(width 0.1)
				(type default)
			)
			(layer "B.Fab")
		)
		(fp_line
			(start 0.67945 0.3048)
			(end 0.67945 -0.305054)
			(stroke
				(width 0.1)
				(type default)
			)
			(layer "B.Fab")
		)
		(pad "1" smd circle
			(at 0.40005 0 180)
			(size 0 0)
			(layers "B.Cu" "B.Mask" "B.Paste")
			(net "SMB_BMC_MM13_R_SDA")
		)
		(pad "2" smd circle
			(at -0.40005 0 180)
			(size 0 0)
			(layers "B.Cu" "B.Mask" "B.Paste")
			(net "SMB_BMC_MM13_SDA")
		)
	)
	(footprint ""
		(layer "B.Cu")
		(at 70.358 -19.685 90)
		(property "Reference" "R865"
			(at 0 0 90)
			(layer "B.SilkS")
			(hide yes)
			(effects
				(font
					(size 1.27 1.27)
				)
				(justify mirror)
			)
		)
		(property "Value" ""
			(at 0 0 90)
			(layer "B.Fab")
			(effects
				(font
					(size 1.27 1.27)
				)
				(justify mirror)
			)
		)
		(duplicate_pad_numbers_are_jumpers no)
		(fp_line
			(start 0.7874 -0.4064)
			(end -0.7874 -0.4064)
			(stroke
				(width 0.1524)
				(type default)
			)
			(layer "B.SilkS")
		)
		(fp_line
			(start -0.7874 -0.4064)
			(end -0.7874 0.4064)
			(stroke
				(width 0.1524)
				(type default)
			)
			(layer "B.SilkS")
		)
		(fp_line
			(start 0.7874 0.4064)
			(end 0.7874 -0.4064)
			(stroke
				(width 0.1524)
				(type default)
			)
			(layer "B.SilkS")
		)
		(fp_line
			(start -0.7874 0.4064)
			(end 0.7874 0.4064)
			(stroke
				(width 0.1524)
				(type default)
			)
			(layer "B.SilkS")
		)
		(fp_line
			(start 0.67945 -0.305054)
			(end 0.12065 -0.305054)
			(stroke
				(width 0.1)
				(type default)
			)
			(layer "B.Fab")
		)
		(fp_line
			(start 0.12065 -0.305054)
			(end 0.12065 -0.2794)
			(stroke
				(width 0.1)
				(type default)
			)
			(layer "B.Fab")
		)
		(fp_line
			(start -0.12065 -0.3048)
			(end -0.67945 -0.3048)
			(stroke
				(width 0.1)
				(type default)
			)
			(layer "B.Fab")
		)
		(fp_line
			(start -0.67945 -0.3048)
			(end -0.67945 0.3048)
			(stroke
				(width 0.1)
				(type default)
			)
			(layer "B.Fab")
		)
		(fp_line
			(start 0.12065 -0.2794)
			(end -0.12065 -0.2794)
			(stroke
				(width 0.1)
				(type default)
			)
			(layer "B.Fab")
		)
		(fp_line
			(start -0.12065 -0.2794)
			(end -0.12065 -0.3048)
			(stroke
				(width 0.1)
				(type default)
			)
			(layer "B.Fab")
		)
		(fp_line
			(start 0.12065 0.2794)
			(end 0.12065 0.3048)
			(stroke
				(width 0.1)
				(type default)
			)
			(layer "B.Fab")
		)
		(fp_line
			(start -0.120396 0.2794)
			(end 0.12065 0.2794)
			(stroke
				(width 0.1)
				(type default)
			)
			(layer "B.Fab")
		)
		(fp_line
			(start 0.67945 0.3048)
			(end 0.67945 -0.305054)
			(stroke
				(width 0.1)
				(type default)
			)
			(layer "B.Fab")
		)
		(fp_line
			(start 0.12065 0.3048)
			(end 0.67945 0.3048)
			(stroke
				(width 0.1)
				(type default)
			)
			(layer "B.Fab")
		)
		(fp_line
			(start -0.120396 0.3048)
			(end -0.120396 0.2794)
			(stroke
				(width 0.1)
				(type default)
			)
			(layer "B.Fab")
		)
		(fp_line
			(start -0.67945 0.3048)
			(end -0.120396 0.3048)
			(stroke
				(width 0.1)
				(type default)
			)
			(layer "B.Fab")
		)
		(pad "1" smd circle
			(at 0.40005 0 270)
			(size 0 0)
			(layers "B.Cu" "B.Mask" "B.Paste")
			(net "FM_BOARD_BMC_REV_ID0")
		)
		(pad "2" smd circle
			(at -0.40005 0 270)
			(size 0 0)
			(layers "B.Cu" "B.Mask" "B.Paste")
			(net "GND")
		)
	)
)
